# S9S_MB_2U (Grand Teton) — schematic netlist excerpt (pin names and nets, part order shuffled) for the footprints in the layout excerpt that follows; sources: Cadence DE-HDL packaged netlist, KiCad conversion of 03242023_DA0F0TMBIJ0_F0T_Motherboard_J_brd_V01_OCP.brd

R4206  Q_RES  1K 1% EMPTY  pkg 0402LF  page 170 : A = P3V3_AUX ; B = U270_0_ADD0
PR145  Q_RES  8.87K 1% EMPTY  pkg 0402LF  page 268 : A = PVCCIN_CPU0_LSET3 ; B = GND

(kicad_pcb
	(version 20260206)
	(generator "pcbnew")
	(generator_version "10.0")
	(general
		(thickness 1.6)
		(legacy_teardrops no)
	)
	(paper "A4")
	(title_block
		(title "03242023_DA0F0TMBIJ0_F0T_Motherboard_J_brd_V01_OCP.brd")
		(comment 1 "Grand Teton / footprints 3018-3019 of 6105")
	)
	(layers
		(0 "F.Cu" signal "TOP")
		(4 "In1.Cu" signal "GND")
		(6 "In2.Cu" signal "IN1")
		(8 "In3.Cu" signal "GND1")
		(10 "In4.Cu" signal "IN2")
		(12 "In5.Cu" signal "GND2")
		(14 "In6.Cu" signal "IN3")
		(16 "In7.Cu" signal "GND3")
		(18 "In8.Cu" signal "VCC")
		(20 "In9.Cu" signal "VCC1")
		(22 "In10.Cu" signal "GND4")
		(24 "In11.Cu" signal "IN4")
		(26 "In12.Cu" signal "GND5")
		(28 "In13.Cu" signal "IN5")
		(30 "In14.Cu" signal "GND6")
		(32 "In15.Cu" signal "IN6")
		(34 "In16.Cu" signal "GND7")
		(2 "B.Cu" signal "BOTTOM")
		(9 "F.Adhes" user "F.Adhesive")
		(11 "B.Adhes" user "B.Adhesive")
		(13 "F.Paste" user "Package Geometry/Pastemask Top")
		(15 "B.Paste" user "Package Geometry/Pastemask Bottom")
		(5 "F.SilkS" user "Ref Des/Silkscreen Top")
		(7 "B.SilkS" user "Ref Des/Silkscreen Bottom")
		(1 "F.Mask" user "Board Geometry/Soldermask Top")
		(3 "B.Mask" user "Board Geometry/Soldermask Bottom")
		(17 "Dwgs.User" user "User.Drawings")
		(19 "Cmts.User" user "User.Comments")
		(21 "Eco1.User" user "User.Eco1")
		(23 "Eco2.User" user "User.Eco2")
		(25 "Edge.Cuts" user "Board Geometry/Outline")
		(27 "Margin" user)
		(31 "F.CrtYd" user "Package Geometry/Place Bound Top")
		(29 "B.CrtYd" user "Package Geometry/Place Bound Bottom")
		(35 "F.Fab" user "Ref Des/Assembly Top")
		(33 "B.Fab" user "Ref Des/Assembly Bottom")
	)
	(footprint ""
		(layer "F.Cu")
		(at 359.967276 -338.86013)
		(property "Reference" "PR145"
			(at 0 0 0)
			(layer "F.SilkS")
			(hide yes)
			(effects
				(font
					(size 1.27 1.27)
				)
			)
		)
		(property "Value" ""
			(at 0 0 0)
			(layer "F.Fab")
			(effects
				(font
					(size 1.27 1.27)
				)
			)
		)
		(duplicate_pad_numbers_are_jumpers no)
		(fp_line
			(start -0.7874 -0.4064)
			(end 0.7874 -0.4064)
			(stroke
				(width 0.1524)
				(type default)
			)
			(layer "F.SilkS")
		)
		(fp_line
			(start -0.7874 0.4064)
			(end -0.7874 -0.4064)
			(stroke
				(width 0.1524)
				(type default)
			)
			(layer "F.SilkS")
		)
		(fp_line
			(start 0.7874 -0.4064)
			(end 0.7874 0.4064)
			(stroke
				(width 0.1524)
				(type default)
			)
			(layer "F.SilkS")
		)
		(fp_line
			(start 0.7874 0.4064)
			(end -0.7874 0.4064)
			(stroke
				(width 0.1524)
				(type default)
			)
			(layer "F.SilkS")
		)
		(fp_line
			(start -0.67945 -0.305054)
			(end -0.12065 -0.305054)
			(stroke
				(width 0.1)
				(type default)
			)
			(layer "F.Fab")
		)
		(fp_line
			(start -0.67945 0.3048)
			(end -0.67945 -0.305054)
			(stroke
				(width 0.1)
				(type default)
			)
			(layer "F.Fab")
		)
		(fp_line
			(start -0.12065 -0.305054)
			(end -0.12065 -0.2794)
			(stroke
				(width 0.1)
				(type default)
			)
			(layer "F.Fab")
		)
		(fp_line
			(start -0.12065 -0.2794)
			(end 0.12065 -0.2794)
			(stroke
				(width 0.1)
				(type default)
			)
			(layer "F.Fab")
		)
		(fp_line
			(start -0.12065 0.2794)
			(end -0.12065 0.3048)
			(stroke
				(width 0.1)
				(type default)
			)
			(layer "F.Fab")
		)
		(fp_line
			(start -0.12065 0.3048)
			(end -0.67945 0.3048)
			(stroke
				(width 0.1)
				(type default)
			)
			(layer "F.Fab")
		)
		(fp_line
			(start 0.120396 0.2794)
			(end -0.12065 0.2794)
			(stroke
				(width 0.1)
				(type default)
			)
			(layer "F.Fab")
		)
		(fp_line
			(start 0.120396 0.3048)
			(end 0.120396 0.2794)
			(stroke
				(width 0.1)
				(type default)
			)
			(layer "F.Fab")
		)
		(fp_line
			(start 0.12065 -0.3048)
			(end 0.67945 -0.3048)
			(stroke
				(width 0.1)
				(type default)
			)
			(layer "F.Fab")
		)
		(fp_line
			(start 0.12065 -0.2794)
			(end 0.12065 -0.3048)
			(stroke
				(width 0.1)
				(type default)
			)
			(layer "F.Fab")
		)
		(fp_line
			(start 0.67945 -0.3048)
			(end 0.67945 0.3048)
			(stroke
				(width 0.1)
				(type default)
			)
			(layer "F.Fab")
		)
		(fp_line
			(start 0.67945 0.3048)
			(end 0.120396 0.3048)
			(stroke
				(width 0.1)
				(type default)
			)
			(layer "F.Fab")
		)
		(pad "1" smd circle
			(at -0.40005 0)
			(size 0 0)
			(layers "F.Cu" "F.Mask" "F.Paste")
			(net "PVCCIN_CPU0_LSET3")
		)
		(pad "2" smd circle
			(at 0.40005 0)
			(size 0 0)
			(layers "F.Cu" "F.Mask" "F.Paste")
			(net "GND")
		)
	)
	(footprint ""
		(layer "F.Cu")
		(at 371.796818 -417.17341 90)
		(property "Reference" "R4206"
			(at 0 0 90)
			(layer "F.SilkS")
			(hide yes)
			(effects
				(font
					(size 1.27 1.27)
				)
			)
		)
		(property "Value" ""
			(at 0 0 90)
			(layer "F.Fab")
			(effects
				(font
					(size 1.27 1.27)
				)
			)
		)
		(duplicate_pad_numbers_are_jumpers no)
		(fp_line
			(start 0.7874 -0.4064)
			(end 0.7874 0.4064)
			(stroke
				(width 0.1524)
				(type default)
			)
			(layer "F.SilkS")
		)
		(fp_line
			(start -0.7874 -0.4064)
			(end 0.7874 -0.4064)
			(stroke
				(width 0.1524)
				(type default)
			)
			(layer "F.SilkS")
		)
		(fp_line
			(start 0.7874 0.4064)
			(end -0.7874 0.4064)
			(stroke
				(width 0.1524)
				(type default)
			)
			(layer "F.SilkS")
		)
		(fp_line
			(start -0.7874 0.4064)
			(end -0.7874 -0.4064)
			(stroke
				(width 0.1524)
				(type default)
			)
			(layer "F.SilkS")
		)
		(fp_line
			(start -0.12065 -0.305054)
			(end -0.12065 -0.2794)
			(stroke
				(width 0.1)
				(type default)
			)
			(layer "F.Fab")
		)
		(fp_line
			(start -0.67945 -0.305054)
			(end -0.12065 -0.305054)
			(stroke
				(width 0.1)
				(type default)
			)
			(layer "F.Fab")
		)
		(fp_line
			(start 0.67945 -0.3048)
			(end 0.67945 0.3048)
			(stroke
				(width 0.1)
				(type default)
			)
			(layer "F.Fab")
		)
		(fp_line
			(start 0.12065 -0.3048)
			(end 0.67945 -0.3048)
			(stroke
				(width 0.1)
				(type default)
			)
			(layer "F.Fab")
		)
		(fp_line
			(start 0.12065 -0.2794)
			(end 0.12065 -0.3048)
			(stroke
				(width 0.1)
				(type default)
			)
			(layer "F.Fab")
		)
		(fp_line
			(start -0.12065 -0.2794)
			(end 0.12065 -0.2794)
			(stroke
				(width 0.1)
				(type default)
			)
			(layer "F.Fab")
		)
		(fp_line
			(start 0.120396 0.2794)
			(end -0.12065 0.2794)
			(stroke
				(width 0.1)
				(type default)
			)
			(layer "F.Fab")
		)
		(fp_line
			(start -0.12065 0.2794)
			(end -0.12065 0.3048)
			(stroke
				(width 0.1)
				(type default)
			)
			(layer "F.Fab")
		)
		(fp_line
			(start 0.67945 0.3048)
			(end 0.120396 0.3048)
			(stroke
				(width 0.1)
				(type default)
			)
			(layer "F.Fab")
		)
		(fp_line
			(start 0.120396 0.3048)
			(end 0.120396 0.2794)
			(stroke
				(width 0.1)
				(type default)
			)
			(layer "F.Fab")
		)
		(fp_line
			(start -0.12065 0.3048)
			(end -0.67945 0.3048)
			(stroke
				(width 0.1)
				(type default)
			)
			(layer "F.Fab")
		)
		(fp_line
			(start -0.67945 0.3048)
			(end -0.67945 -0.305054)
			(stroke
				(width 0.1)
				(type default)
			)
			(layer "F.Fab")
		)
		(pad "1" smd circle
			(at -0.40005 0 90)
			(size 0 0)
			(layers "F.Cu" "F.Mask" "F.Paste")
			(net "P3V3_AUX")
		)
		(pad "2" smd circle
			(at 0.40005 0 90)
			(size 0 0)
			(layers "F.Cu" "F.Mask" "F.Paste")
			(net "U270_0_ADD0")
		)
	)
)
